(kicad_pcb
	(version 20260206)
	(generator "pcbnew")
	(generator_version "10.0")
	(general
		(thickness 1.6)
		(legacy_teardrops no)
	)
	(paper "A4")
	(title_block
		(title "03242023_DA0F0TMBIJ0_F0T_Motherboard_J_brd_V01_OCP.brd")
		(comment 1 "Grand Teton / footprints 85-91 of 6105")
	)
	(layers
		(0 "F.Cu" signal "TOP")
		(4 "In1.Cu" signal "GND")
		(6 "In2.Cu" signal "IN1")
		(8 "In3.Cu" signal "GND1")
		(10 "In4.Cu" signal "IN2")
		(12 "In5.Cu" signal "GND2")
		(14 "In6.Cu" signal "IN3")
		(16 "In7.Cu" signal "GND3")
		(18 "In8.Cu" signal "VCC")
		(20 "In9.Cu" signal "VCC1")
		(22 "In10.Cu" signal "GND4")
		(24 "In11.Cu" signal "IN4")
		(26 "In12.Cu" signal "GND5")
		(28 "In13.Cu" signal "IN5")
		(30 "In14.Cu" signal "GND6")
		(32 "In15.Cu" signal "IN6")
		(34 "In16.Cu" signal "GND7")
		(2 "B.Cu" signal "BOTTOM")
		(9 "F.Adhes" user "F.Adhesive")
		(11 "B.Adhes" user "B.Adhesive")
		(13 "F.Paste" user "Package Geometry/Pastemask Top")
		(15 "B.Paste" user "Package Geometry/Pastemask Bottom")
		(5 "F.SilkS" user "Ref Des/Silkscreen Top")
		(7 "B.SilkS" user "Ref Des/Silkscreen Bottom")
		(1 "F.Mask" user "Board Geometry/Soldermask Top")
		(3 "B.Mask" user "Board Geometry/Soldermask Bottom")
		(17 "Dwgs.User" user "User.Drawings")
		(19 "Cmts.User" user "User.Comments")
		(21 "Eco1.User" user "User.Eco1")
		(23 "Eco2.User" user "User.Eco2")
		(25 "Edge.Cuts" user "Board Geometry/Outline")
		(27 "Margin" user)
		(31 "F.CrtYd" user "Package Geometry/Place Bound Top")
		(29 "B.CrtYd" user "Package Geometry/Place Bound Bottom")
		(35 "F.Fab" user "Ref Des/Assembly Top")
		(33 "B.Fab" user "Ref Des/Assembly Bottom")
	)
	(footprint ""
		(layer "F.Cu")
		(at 385.384802 -49.488598 90)
		(property "Reference" "R765"
			(at 0 0 90)
			(layer "F.SilkS")
			(hide yes)
			(effects
				(font
					(size 1.27 1.27)
				)
			)
		)
		(property "Value" ""
			(at 0 0 90)
			(layer "F.Fab")
			(effects
				(font
					(size 1.27 1.27)
				)
			)
		)
		(duplicate_pad_numbers_are_jumpers no)
		(fp_line
			(start 0.7874 -0.4064)
			(end 0.7874 0.4064)
			(stroke
				(width 0.1524)
				(type default)
			)
			(layer "F.SilkS")
		)
		(fp_line
			(start -0.7874 -0.4064)
			(end 0.7874 -0.4064)
			(stroke
				(width 0.1524)
				(type default)
			)
			(layer "F.SilkS")
		)
		(fp_line
			(start 0.7874 0.4064)
			(end -0.7874 0.4064)
			(stroke
				(width 0.1524)
				(type default)
			)
			(layer "F.SilkS")
		)
		(fp_line
			(start -0.7874 0.4064)
			(end -0.7874 -0.4064)
			(stroke
				(width 0.1524)
				(type default)
			)
			(layer "F.SilkS")
		)
		(fp_line
			(start -0.12065 -0.305054)
			(end -0.12065 -0.2794)
			(stroke
				(width 0.1)
				(type default)
			)
			(layer "F.Fab")
		)
		(fp_line
			(start -0.67945 -0.305054)
			(end -0.12065 -0.305054)
			(stroke
				(width 0.1)
				(type default)
			)
			(layer "F.Fab")
		)
		(fp_line
			(start 0.67945 -0.3048)
			(end 0.67945 0.3048)
			(stroke
				(width 0.1)
				(type default)
			)
			(layer "F.Fab")
		)
		(fp_line
			(start 0.12065 -0.3048)
			(end 0.67945 -0.3048)
			(stroke
				(width 0.1)
				(type default)
			)
			(layer "F.Fab")
		)
		(fp_line
			(start 0.12065 -0.2794)
			(end 0.12065 -0.3048)
			(stroke
				(width 0.1)
				(type default)
			)
			(layer "F.Fab")
		)
		(fp_line
			(start -0.12065 -0.2794)
			(end 0.12065 -0.2794)
			(stroke
				(width 0.1)
				(type default)
			)
			(layer "F.Fab")
		)
		(fp_line
			(start 0.120396 0.2794)
			(end -0.12065 0.2794)
			(stroke
				(width 0.1)
				(type default)
			)
			(layer "F.Fab")
		)
		(fp_line
			(start -0.12065 0.2794)
			(end -0.12065 0.3048)
			(stroke
				(width 0.1)
				(type default)
			)
			(layer "F.Fab")
		)
		(fp_line
			(start 0.67945 0.3048)
			(end 0.120396 0.3048)
			(stroke
				(width 0.1)
				(type default)
			)
			(layer "F.Fab")
		)
		(fp_line
			(start 0.120396 0.3048)
			(end 0.120396 0.2794)
			(stroke
				(width 0.1)
				(type default)
			)
			(layer "F.Fab")
		)
		(fp_line
			(start -0.12065 0.3048)
			(end -0.67945 0.3048)
			(stroke
				(width 0.1)
				(type default)
			)
			(layer "F.Fab")
		)
		(fp_line
			(start -0.67945 0.3048)
			(end -0.67945 -0.305054)
			(stroke
				(width 0.1)
				(type default)
			)
			(layer "F.Fab")
		)
		(pad "1" smd circle
			(at -0.40005 0 90)
			(size 0 0)
			(layers "F.Cu" "F.Mask" "F.Paste")
			(net "JTAG_DBP_TCK_PCH")
		)
		(pad "2" smd circle
			(at 0.40005 0 90)
			(size 0 0)
			(layers "F.Cu" "F.Mask" "F.Paste")
			(net "JTAG_DBP_TCK_R_TCK")
		)
	)
	(footprint ""
		(layer "F.Cu")
		(at 54.242716 -106.86669 180)
		(property "Reference" "R3719"
			(at 0 0 180)
			(layer "F.SilkS")
			(hide yes)
			(effects
				(font
					(size 1.27 1.27)
				)
			)
		)
		(property "Value" ""
			(at 0 0 180)
			(layer "F.Fab")
			(effects
				(font
					(size 1.27 1.27)
				)
			)
		)
		(duplicate_pad_numbers_are_jumpers no)
		(fp_line
			(start 0.7874 0.4064)
			(end -0.7874 0.4064)
			(stroke
				(width 0.1524)
				(type default)
			)
			(layer "F.SilkS")
		)
		(fp_line
			(start 0.7874 -0.4064)
			(end 0.7874 0.4064)
			(stroke
				(width 0.1524)
				(type default)
			)
			(layer "F.SilkS")
		)
		(fp_line
			(start -0.7874 0.4064)
			(end -0.7874 -0.4064)
			(stroke
				(width 0.1524)
				(type default)
			)
			(layer "F.SilkS")
		)
		(fp_line
			(start -0.7874 -0.4064)
			(end 0.7874 -0.4064)
			(stroke
				(width 0.1524)
				(type default)
			)
			(layer "F.SilkS")
		)
		(fp_line
			(start 0.67945 0.3048)
			(end 0.120396 0.3048)
			(stroke
				(width 0.1)
				(type default)
			)
			(layer "F.Fab")
		)
		(fp_line
			(start 0.67945 -0.3048)
			(end 0.67945 0.3048)
			(stroke
				(width 0.1)
				(type default)
			)
			(layer "F.Fab")
		)
		(fp_line
			(start 0.12065 -0.2794)
			(end 0.12065 -0.3048)
			(stroke
				(width 0.1)
				(type default)
			)
			(layer "F.Fab")
		)
		(fp_line
			(start 0.12065 -0.3048)
			(end 0.67945 -0.3048)
			(stroke
				(width 0.1)
				(type default)
			)
			(layer "F.Fab")
		)
		(fp_line
			(start 0.120396 0.3048)
			(end 0.120396 0.2794)
			(stroke
				(width 0.1)
				(type default)
			)
			(layer "F.Fab")
		)
		(fp_line
			(start 0.120396 0.2794)
			(end -0.12065 0.2794)
			(stroke
				(width 0.1)
				(type default)
			)
			(layer "F.Fab")
		)
		(fp_line
			(start -0.12065 0.3048)
			(end -0.67945 0.3048)
			(stroke
				(width 0.1)
				(type default)
			)
			(layer "F.Fab")
		)
		(fp_line
			(start -0.12065 0.2794)
			(end -0.12065 0.3048)
			(stroke
				(width 0.1)
				(type default)
			)
			(layer "F.Fab")
		)
		(fp_line
			(start -0.12065 -0.2794)
			(end 0.12065 -0.2794)
			(stroke
				(width 0.1)
				(type default)
			)
			(layer "F.Fab")
		)
		(fp_line
			(start -0.12065 -0.305054)
			(end -0.12065 -0.2794)
			(stroke
				(width 0.1)
				(type default)
			)
			(layer "F.Fab")
		)
		(fp_line
			(start -0.67945 0.3048)
			(end -0.67945 -0.305054)
			(stroke
				(width 0.1)
				(type default)
			)
			(layer "F.Fab")
		)
		(fp_line
			(start -0.67945 -0.305054)
			(end -0.12065 -0.305054)
			(stroke
				(width 0.1)
				(type default)
			)
			(layer "F.Fab")
		)
		(pad "1" smd circle
			(at -0.40005 0 180)
			(size 0 0)
			(layers "F.Cu" "F.Mask" "F.Paste")
			(net "SMB_LM75_2_3V3AUX_SCL_R")
		)
		(pad "2" smd circle
			(at 0.40005 0 180)
			(size 0 0)
			(layers "F.Cu" "F.Mask" "F.Paste")
			(net "SMB_LM75_2_3V3AUX_SCL")
		)
	)
	(footprint ""
		(layer "F.Cu")
		(at 345.123008 -408.517344 -90)
		(property "Reference" "C928"
			(at 0 0 270)
			(layer "F.SilkS")
			(hide yes)
			(effects
				(font
					(size 1.27 1.27)
				)
			)
		)
		(property "Value" ""
			(at 0 0 270)
			(layer "F.Fab")
			(effects
				(font
					(size 1.27 1.27)
				)
			)
		)
		(duplicate_pad_numbers_are_jumpers no)
		(fp_line
			(start -0.299974 0.150114)
			(end -0.299974 -0.150114)
			(stroke
				(width 0.1)
				(type default)
			)
			(layer "F.Fab")
		)
		(fp_line
			(start 0.299974 0.150114)
			(end -0.299974 0.150114)
			(stroke
				(width 0.1)
				(type default)
			)
			(layer "F.Fab")
		)
		(fp_line
			(start -0.299974 -0.150114)
			(end 0.299974 -0.150114)
			(stroke
				(width 0.1)
				(type default)
			)
			(layer "F.Fab")
		)
		(fp_line
			(start 0.299974 -0.150114)
			(end 0.299974 0.150114)
			(stroke
				(width 0.1)
				(type default)
			)
			(layer "F.Fab")
		)
		(pad "1" smd rect
			(at -0.2667 0 270)
			(size 0.3048 0.381)
			(layers "F.Cu" "F.Mask" "F.Paste")
			(net "P5E_CPU0_PE0_TX_C_DN<2>")
		)
		(pad "2" smd rect
			(at 0.2667 0 270)
			(size 0.3048 0.381)
			(layers "F.Cu" "F.Mask" "F.Paste")
			(net "P5E_CPU0_PE0_TX_DN<2>")
		)
	)
	(footprint ""
		(layer "F.Cu")
		(at 252.780292 -407.416 -90)
		(property "Reference" "PR2533"
			(at 0 0 270)
			(layer "F.SilkS")
			(hide yes)
			(effects
				(font
					(size 1.27 1.27)
				)
			)
		)
		(property "Value" ""
			(at 0 0 270)
			(layer "F.Fab")
			(effects
				(font
					(size 1.27 1.27)
				)
			)
		)
		(duplicate_pad_numbers_are_jumpers no)
		(fp_line
			(start -3.9878 3.5814)
			(end -3.9878 -3.5814)
			(stroke
				(width 0.1524)
				(type default)
			)
			(layer "F.SilkS")
		)
		(fp_line
			(start 3.9878 3.5814)
			(end -3.9878 3.5814)
			(stroke
				(width 0.1524)
				(type default)
			)
			(layer "F.SilkS")
		)
		(fp_line
			(start -3.9878 -3.5814)
			(end 3.9878 -3.5814)
			(stroke
				(width 0.1524)
				(type default)
			)
			(layer "F.SilkS")
		)
		(fp_line
			(start 3.9878 -3.5814)
			(end 3.9878 3.5814)
			(stroke
				(width 0.1524)
				(type default)
			)
			(layer "F.SilkS")
		)
		(fp_line
			(start -3.5306 3.353054)
			(end -3.5306 -3.353054)
			(stroke
				(width 0.1)
				(type default)
			)
			(layer "F.Fab")
		)
		(fp_line
			(start 3.5306 3.353054)
			(end -3.5306 3.353054)
			(stroke
				(width 0.1)
				(type default)
			)
			(layer "F.Fab")
		)
		(fp_line
			(start -3.5306 -3.353054)
			(end 3.5306 -3.353054)
			(stroke
				(width 0.1)
				(type default)
			)
			(layer "F.Fab")
		)
		(fp_line
			(start 3.5306 -3.353054)
			(end 3.5306 3.353054)
			(stroke
				(width 0.1)
				(type default)
			)
			(layer "F.Fab")
		)
		(pad "1A" smd rect
			(at -2.249932 0 90)
			(size 3.2004 6.858)
			(layers "F.Cu" "F.Mask" "F.Paste")
			(net "P12V_PSU")
		)
		(pad "1B" smd rect
			(at -0.776732 0 270)
			(size 0.254 0.508)
			(layers "F.Cu" "F.Mask" "F.Paste")
			(net "P12V_HSC_SENSE2_R3_P")
		)
		(pad "2A" smd rect
			(at 2.249932 0 90)
			(size 3.2004 6.858)
			(layers "F.Cu" "F.Mask" "F.Paste")
			(net "P12V_MAIN_R")
		)
		(pad "2B" smd rect
			(at 0.776732 0 270)
			(size 0.254 0.508)
			(layers "F.Cu" "F.Mask" "F.Paste")
			(net "P12V_HSC_SENSE2_R3_N")
		)
	)
	(footprint ""
		(layer "F.Cu")
		(at 354.731828 -400.328638 180)
		(property "Reference" "R2666"
			(at 0 0 180)
			(layer "F.SilkS")
			(hide yes)
			(effects
				(font
					(size 1.27 1.27)
				)
			)
		)
		(property "Value" ""
			(at 0 0 180)
			(layer "F.Fab")
			(effects
				(font
					(size 1.27 1.27)
				)
			)
		)
		(duplicate_pad_numbers_are_jumpers no)
		(fp_line
			(start 0.7874 0.4064)
			(end -0.7874 0.4064)
			(stroke
				(width 0.1524)
				(type default)
			)
			(layer "F.SilkS")
		)
		(fp_line
			(start 0.7874 -0.4064)
			(end 0.7874 0.4064)
			(stroke
				(width 0.1524)
				(type default)
			)
			(layer "F.SilkS")
		)
		(fp_line
			(start -0.7874 0.4064)
			(end -0.7874 -0.4064)
			(stroke
				(width 0.1524)
				(type default)
			)
			(layer "F.SilkS")
		)
		(fp_line
			(start -0.7874 -0.4064)
			(end 0.7874 -0.4064)
			(stroke
				(width 0.1524)
				(type default)
			)
			(layer "F.SilkS")
		)
		(fp_line
			(start 0.67945 0.3048)
			(end 0.120396 0.3048)
			(stroke
				(width 0.1)
				(type default)
			)
			(layer "F.Fab")
		)
		(fp_line
			(start 0.67945 -0.3048)
			(end 0.67945 0.3048)
			(stroke
				(width 0.1)
				(type default)
			)
			(layer "F.Fab")
		)
		(fp_line
			(start 0.12065 -0.2794)
			(end 0.12065 -0.3048)
			(stroke
				(width 0.1)
				(type default)
			)
			(layer "F.Fab")
		)
		(fp_line
			(start 0.12065 -0.3048)
			(end 0.67945 -0.3048)
			(stroke
				(width 0.1)
				(type default)
			)
			(layer "F.Fab")
		)
		(fp_line
			(start 0.120396 0.3048)
			(end 0.120396 0.2794)
			(stroke
				(width 0.1)
				(type default)
			)
			(layer "F.Fab")
		)
		(fp_line
			(start 0.120396 0.2794)
			(end -0.12065 0.2794)
			(stroke
				(width 0.1)
				(type default)
			)
			(layer "F.Fab")
		)
		(fp_line
			(start -0.12065 0.3048)
			(end -0.67945 0.3048)
			(stroke
				(width 0.1)
				(type default)
			)
			(layer "F.Fab")
		)
		(fp_line
			(start -0.12065 0.2794)
			(end -0.12065 0.3048)
			(stroke
				(width 0.1)
				(type default)
			)
			(layer "F.Fab")
		)
		(fp_line
			(start -0.12065 -0.2794)
			(end 0.12065 -0.2794)
			(stroke
				(width 0.1)
				(type default)
			)
			(layer "F.Fab")
		)
		(fp_line
			(start -0.12065 -0.305054)
			(end -0.12065 -0.2794)
			(stroke
				(width 0.1)
				(type default)
			)
			(layer "F.Fab")
		)
		(fp_line
			(start -0.67945 0.3048)
			(end -0.67945 -0.305054)
			(stroke
				(width 0.1)
				(type default)
			)
			(layer "F.Fab")
		)
		(fp_line
			(start -0.67945 -0.305054)
			(end -0.12065 -0.305054)
			(stroke
				(width 0.1)
				(type default)
			)
			(layer "F.Fab")
		)
		(pad "1" smd circle
			(at -0.40005 0 180)
			(size 0 0)
			(layers "F.Cu" "F.Mask" "F.Paste")
			(net "SMB_BMC_SWB_EN")
		)
		(pad "2" smd circle
			(at 0.40005 0 180)
			(size 0 0)
			(layers "F.Cu" "F.Mask" "F.Paste")
			(net "GND")
		)
	)
	(footprint ""
		(layer "F.Cu")
		(at 297.41622 -421.41521 90)
		(property "Reference" "R4133"
			(at 0 0 90)
			(layer "F.SilkS")
			(hide yes)
			(effects
				(font
					(size 1.27 1.27)
				)
			)
		)
		(property "Value" ""
			(at 0 0 90)
			(layer "F.Fab")
			(effects
				(font
					(size 1.27 1.27)
				)
			)
		)
		(duplicate_pad_numbers_are_jumpers no)
		(fp_line
			(start 0.7874 -0.4064)
			(end 0.7874 0.4064)
			(stroke
				(width 0.1524)
				(type default)
			)
			(layer "F.SilkS")
		)
		(fp_line
			(start -0.7874 -0.4064)
			(end 0.7874 -0.4064)
			(stroke
				(width 0.1524)
				(type default)
			)
			(layer "F.SilkS")
		)
		(fp_line
			(start 0.7874 0.4064)
			(end -0.7874 0.4064)
			(stroke
				(width 0.1524)
				(type default)
			)
			(layer "F.SilkS")
		)
		(fp_line
			(start -0.7874 0.4064)
			(end -0.7874 -0.4064)
			(stroke
				(width 0.1524)
				(type default)
			)
			(layer "F.SilkS")
		)
		(fp_line
			(start -0.12065 -0.305054)
			(end -0.12065 -0.2794)
			(stroke
				(width 0.1)
				(type default)
			)
			(layer "F.Fab")
		)
		(fp_line
			(start -0.67945 -0.305054)
			(end -0.12065 -0.305054)
			(stroke
				(width 0.1)
				(type default)
			)
			(layer "F.Fab")
		)
		(fp_line
			(start 0.67945 -0.3048)
			(end 0.67945 0.3048)
			(stroke
				(width 0.1)
				(type default)
			)
			(layer "F.Fab")
		)
		(fp_line
			(start 0.12065 -0.3048)
			(end 0.67945 -0.3048)
			(stroke
				(width 0.1)
				(type default)
			)
			(layer "F.Fab")
		)
		(fp_line
			(start 0.12065 -0.2794)
			(end 0.12065 -0.3048)
			(stroke
				(width 0.1)
				(type default)
			)
			(layer "F.Fab")
		)
		(fp_line
			(start -0.12065 -0.2794)
			(end 0.12065 -0.2794)
			(stroke
				(width 0.1)
				(type default)
			)
			(layer "F.Fab")
		)
		(fp_line
			(start 0.120396 0.2794)
			(end -0.12065 0.2794)
			(stroke
				(width 0.1)
				(type default)
			)
			(layer "F.Fab")
		)
		(fp_line
			(start -0.12065 0.2794)
			(end -0.12065 0.3048)
			(stroke
				(width 0.1)
				(type default)
			)
			(layer "F.Fab")
		)
		(fp_line
			(start 0.67945 0.3048)
			(end 0.120396 0.3048)
			(stroke
				(width 0.1)
				(type default)
			)
			(layer "F.Fab")
		)
		(fp_line
			(start 0.120396 0.3048)
			(end 0.120396 0.2794)
			(stroke
				(width 0.1)
				(type default)
			)
			(layer "F.Fab")
		)
		(fp_line
			(start -0.12065 0.3048)
			(end -0.67945 0.3048)
			(stroke
				(width 0.1)
				(type default)
			)
			(layer "F.Fab")
		)
		(fp_line
			(start -0.67945 0.3048)
			(end -0.67945 -0.305054)
			(stroke
				(width 0.1)
				(type default)
			)
			(layer "F.Fab")
		)
		(pad "1" smd circle
			(at -0.40005 0 90)
			(size 0 0)
			(layers "F.Cu" "F.Mask" "F.Paste")
			(net "P3V3_AUX")
		)
		(pad "2" smd circle
			(at 0.40005 0 90)
			(size 0 0)
			(layers "F.Cu" "F.Mask" "F.Paste")
			(net "GPU_3V3IO_RSVD5_FFU")
		)
	)
	(footprint ""
		(layer "F.Cu")
		(at 23.431754 -399.532094 90)
		(property "Reference" "R3284"
			(at 0 0 90)
			(layer "F.SilkS")
			(hide yes)
			(effects
				(font
					(size 1.27 1.27)
				)
			)
		)
		(property "Value" ""
			(at 0 0 90)
			(layer "F.Fab")
			(effects
				(font
					(size 1.27 1.27)
				)
			)
		)
		(duplicate_pad_numbers_are_jumpers no)
		(fp_line
			(start 0.7874 -0.4064)
			(end 0.7874 0.4064)
			(stroke
				(width 0.1524)
				(type default)
			)
			(layer "F.SilkS")
		)
		(fp_line
			(start -0.7874 -0.4064)
			(end 0.7874 -0.4064)
			(stroke
				(width 0.1524)
				(type default)
			)
			(layer "F.SilkS")
		)
		(fp_line
			(start 0.7874 0.4064)
			(end -0.7874 0.4064)
			(stroke
				(width 0.1524)
				(type default)
			)
			(layer "F.SilkS")
		)
		(fp_line
			(start -0.7874 0.4064)
			(end -0.7874 -0.4064)
			(stroke
				(width 0.1524)
				(type default)
			)
			(layer "F.SilkS")
		)
		(fp_line
			(start -0.12065 -0.305054)
			(end -0.12065 -0.2794)
			(stroke
				(width 0.1)
				(type default)
			)
			(layer "F.Fab")
		)
		(fp_line
			(start -0.67945 -0.305054)
			(end -0.12065 -0.305054)
			(stroke
				(width 0.1)
				(type default)
			)
			(layer "F.Fab")
		)
		(fp_line
			(start 0.67945 -0.3048)
			(end 0.67945 0.3048)
			(stroke
				(width 0.1)
				(type default)
			)
			(layer "F.Fab")
		)
		(fp_line
			(start 0.12065 -0.3048)
			(end 0.67945 -0.3048)
			(stroke
				(width 0.1)
				(type default)
			)
			(layer "F.Fab")
		)
		(fp_line
			(start 0.12065 -0.2794)
			(end 0.12065 -0.3048)
			(stroke
				(width 0.1)
				(type default)
			)
			(layer "F.Fab")
		)
		(fp_line
			(start -0.12065 -0.2794)
			(end 0.12065 -0.2794)
			(stroke
				(width 0.1)
				(type default)
			)
			(layer "F.Fab")
		)
		(fp_line
			(start 0.120396 0.2794)
			(end -0.12065 0.2794)
			(stroke
				(width 0.1)
				(type default)
			)
			(layer "F.Fab")
		)
		(fp_line
			(start -0.12065 0.2794)
			(end -0.12065 0.3048)
			(stroke
				(width 0.1)
				(type default)
			)
			(layer "F.Fab")
		)
		(fp_line
			(start 0.67945 0.3048)
			(end 0.120396 0.3048)
			(stroke
				(width 0.1)
				(type default)
			)
			(layer "F.Fab")
		)
		(fp_line
			(start 0.120396 0.3048)
			(end 0.120396 0.2794)
			(stroke
				(width 0.1)
				(type default)
			)
			(layer "F.Fab")
		)
		(fp_line
			(start -0.12065 0.3048)
			(end -0.67945 0.3048)
			(stroke
				(width 0.1)
				(type default)
			)
			(layer "F.Fab")
		)
		(fp_line
			(start -0.67945 0.3048)
			(end -0.67945 -0.305054)
			(stroke
				(width 0.1)
				(type default)
			)
			(layer "F.Fab")
		)
		(pad "1" smd circle
			(at -0.40005 0 90)
			(size 0 0)
			(layers "F.Cu" "F.Mask" "F.Paste")
			(net "FM_P2E_EQB0")
		)
		(pad "2" smd circle
			(at 0.40005 0 90)
			(size 0 0)
			(layers "F.Cu" "F.Mask" "F.Paste")
			(net "GND")
		)
	)
)
